# BASEBOARD_FAB2 (Tioga Pass) — schematic netlist excerpt (pin names and nets, part order shuffled) for the footprints in the layout excerpt that follows; sources: Cadence DE-HDL packaged netlist, KiCad conversion of Wiwynn_Tioga_Pass_MB.brd

Q25W5  FET_N  2N7002 FET  pkg SOT23LF  page 255
  GATE  = BMC_JTAG_SEL_N
  SRC  = GND
  DRN  = BMC_JTAG_SEL

R25W186  RES  0.0 5% CHIP  pkg 0402  page 189 : A = BMC_JTAG_SEL_N ; B = FM_JTAG_PLD_EN_DEBUG
C1R30  CAP  10UF 6.3V 20% X6S  pkg 0603  page 139 : A = P1V5_LAN ; B = GND

(kicad_pcb
	(version 20260206)
	(generator "pcbnew")
	(generator_version "10.0")
	(general
		(thickness 1.6)
		(legacy_teardrops no)
	)
	(paper "A4")
	(title_block
		(title "Wiwynn_Tioga_Pass_MB.brd")
		(comment 1 "Tioga Pass / footprints 3171-3173 of 4770")
	)
	(layers
		(0 "F.Cu" signal "TOP")
		(4 "In1.Cu" signal "L2GND")
		(6 "In2.Cu" signal "L3")
		(8 "In3.Cu" signal "L4GND")
		(10 "In4.Cu" signal "L5")
		(12 "In5.Cu" signal "L6GND")
		(14 "In6.Cu" signal "L7VCC")
		(16 "In7.Cu" signal "L8VCC")
		(18 "In8.Cu" signal "L9GND")
		(20 "In9.Cu" signal "L10")
		(22 "In10.Cu" signal "L11GND")
		(24 "In11.Cu" signal "L12")
		(26 "In12.Cu" signal "L13GND")
		(2 "B.Cu" signal "BOTTOM")
		(9 "F.Adhes" user "F.Adhesive")
		(11 "B.Adhes" user "B.Adhesive")
		(13 "F.Paste" user "Package Geometry/Pastemask Top")
		(15 "B.Paste" user "Package Geometry/Pastemask Bottom")
		(5 "F.SilkS" user "Ref Des/Silkscreen Top")
		(7 "B.SilkS" user "Ref Des/Silkscreen Bottom")
		(1 "F.Mask" user "Board Geometry/Soldermask Top")
		(3 "B.Mask" user "Board Geometry/Soldermask Bottom")
		(17 "Dwgs.User" user "User.Drawings")
		(19 "Cmts.User" user "User.Comments")
		(21 "Eco1.User" user "User.Eco1")
		(23 "Eco2.User" user "User.Eco2")
		(25 "Edge.Cuts" user "Board Geometry/Outline")
		(27 "Margin" user)
		(31 "F.CrtYd" user "Package Geometry/Place Bound Top")
		(29 "B.CrtYd" user "Package Geometry/Place Bound Bottom")
		(35 "F.Fab" user "Ref Des/Assembly Top")
		(33 "B.Fab" user "Ref Des/Assembly Bottom")
	)
	(footprint ""
		(layer "B.Cu")
		(at 479.9076 -41.529 90)
		(property "Reference" "C1R30"
			(at 0 0 90)
			(layer "B.SilkS")
			(hide yes)
			(effects
				(font
					(size 1.27 1.27)
				)
				(justify mirror)
			)
		)
		(property "Value" ""
			(at 0 0 90)
			(layer "B.Fab")
			(effects
				(font
					(size 1.27 1.27)
				)
				(justify mirror)
			)
		)
		(duplicate_pad_numbers_are_jumpers no)
		(fp_poly
			(pts
				(xy 0.4953 -0.2032) (xy -0.4953 -0.2032) (xy -0.4953 1.6002) (xy 0.4953 1.6002)
			)
			(stroke
				(width 0)
				(type default)
			)
			(fill no)
			(layer "B.CrtYd")
		)
		(fp_line
			(start 0.4953 -0.2032)
			(end -0.4953 -0.2032)
			(stroke
				(width 0.1)
				(type default)
			)
			(layer "B.Fab")
		)
		(fp_line
			(start -0.4953 -0.2032)
			(end -0.4953 1.6002)
			(stroke
				(width 0.1)
				(type default)
			)
			(layer "B.Fab")
		)
		(fp_line
			(start 0.4953 1.6002)
			(end 0.4953 -0.2032)
			(stroke
				(width 0.1)
				(type default)
			)
			(layer "B.Fab")
		)
		(fp_line
			(start -0.4953 1.6002)
			(end 0.4953 1.6002)
			(stroke
				(width 0.1)
				(type default)
			)
			(layer "B.Fab")
		)
		(pad "1" smd rect
			(at 0 0 270)
			(size 0.762 0.889)
			(layers "B.Cu" "B.Mask" "B.Paste")
			(net "P1V5_LAN")
		)
		(pad "2" smd rect
			(at 0 1.397 270)
			(size 0.762 0.889)
			(layers "B.Cu" "B.Mask" "B.Paste")
			(net "GND")
		)
		(zone
			(layer "B.Cu")
			(hatch none 0.5)
			(connect_pads
				(clearance 0)
			)
			(min_thickness 0.25)
			(keepout
				(tracks not_allowed)
				(vias allowed)
				(pads allowed)
				(copperpour not_allowed)
				(footprints allowed)
			)
			(placement
				(enabled no)
				(sheetname "")
			)
			(fill
				(thermal_gap 0.5)
				(thermal_bridge_width 0.5)
				(island_removal_mode 0)
			)
			(polygon
				(pts
					(xy 480.3521 -41.91) (xy 480.3521 -41.148) (xy 480.8601 -41.148) (xy 480.8601 -41.91)
				)
			)
		)
	)
	(footprint ""
		(layer "B.Cu")
		(at 437.642 -141.986)
		(property "Reference" "R25W186"
			(at 0.8382 -0.67818 0)
			(unlocked yes)
			(layer "B.SilkS")
			(effects
				(font
					(size 0.4064 0.254)
					(thickness 0.1524)
				)
				(justify left mirror)
			)
		)
		(property "Value" ""
			(at 0 0 0)
			(layer "B.Fab")
			(effects
				(font
					(size 1.27 1.27)
				)
				(justify mirror)
			)
		)
		(duplicate_pad_numbers_are_jumpers no)
		(fp_poly
			(pts
				(xy 0.2794 -0.1016) (xy -0.2794 -0.1016) (xy -0.2794 0.9906) (xy 0.2794 0.9906)
			)
			(stroke
				(width 0)
				(type default)
			)
			(fill no)
			(layer "B.CrtYd")
		)
		(fp_line
			(start -0.2794 -0.1016)
			(end 0.2794 -0.1016)
			(stroke
				(width 0.1)
				(type default)
			)
			(layer "B.Fab")
		)
		(fp_line
			(start -0.2794 0.9906)
			(end -0.2794 -0.1016)
			(stroke
				(width 0.1)
				(type default)
			)
			(layer "B.Fab")
		)
		(fp_line
			(start 0.2794 -0.1016)
			(end 0.2794 0.9906)
			(stroke
				(width 0.1)
				(type default)
			)
			(layer "B.Fab")
		)
		(fp_line
			(start 0.2794 0.9906)
			(end -0.2794 0.9906)
			(stroke
				(width 0.1)
				(type default)
			)
			(layer "B.Fab")
		)
		(pad "1" smd rect
			(at 0 0 180)
			(size 0.508 0.508)
			(layers "B.Cu" "B.Mask" "B.Paste")
			(net "BMC_JTAG_SEL_N")
		)
		(pad "2" smd rect
			(at 0 0.889 180)
			(size 0.508 0.508)
			(layers "B.Cu" "B.Mask" "B.Paste")
			(net "FM_JTAG_PLD_EN_DEBUG")
		)
		(zone
			(layer "B.Cu")
			(hatch none 0.5)
			(connect_pads
				(clearance 0)
			)
			(min_thickness 0.25)
			(keepout
				(tracks allowed)
				(vias not_allowed)
				(pads allowed)
				(copperpour not_allowed)
				(footprints allowed)
			)
			(placement
				(enabled no)
				(sheetname "")
			)
			(fill
				(thermal_gap 0.5)
				(thermal_bridge_width 0.5)
				(island_removal_mode 0)
			)
			(polygon
				(pts
					(xy 437.896 -141.732) (xy 437.388 -141.732) (xy 437.388 -141.351) (xy 437.896 -141.351)
				)
			)
		)
		(zone
			(layer "B.Cu")
			(hatch none 0.5)
			(connect_pads
				(clearance 0)
			)
			(min_thickness 0.25)
			(keepout
				(tracks not_allowed)
				(vias allowed)
				(pads allowed)
				(copperpour not_allowed)
				(footprints allowed)
			)
			(placement
				(enabled no)
				(sheetname "")
			)
			(fill
				(thermal_gap 0.5)
				(thermal_bridge_width 0.5)
				(island_removal_mode 0)
			)
			(polygon
				(pts
					(xy 437.896 -141.351) (xy 437.388 -141.351) (xy 437.388 -141.732) (xy 437.896 -141.732)
				)
			)
		)
	)
	(footprint ""
		(layer "B.Cu")
		(at 448.6656 -151.384 180)
		(property "Reference" "Q25W5"
			(at 0.229362 -1.59512 180)
			(unlocked yes)
			(layer "B.SilkS")
			(effects
				(font
					(size 1.27 0.9652)
					(thickness 0.1524)
				)
				(justify left mirror)
			)
		)
		(property "Value" ""
			(at 0 0 0)
			(layer "B.Fab")
			(effects
				(font
					(size 1.27 1.27)
				)
				(justify mirror)
			)
		)
		(duplicate_pad_numbers_are_jumpers no)
		(fp_line
			(start -0.381 0.635)
			(end -0.381 1.27)
			(stroke
				(width 0.1524)
				(type default)
			)
			(layer "B.SilkS")
		)
		(fp_line
			(start -0.9525 2.4765)
			(end -1.778 2.4765)
			(stroke
				(width 0.1524)
				(type default)
			)
			(layer "B.SilkS")
		)
		(fp_line
			(start -0.9525 -0.5715)
			(end -1.778 -0.5715)
			(stroke
				(width 0.1524)
				(type default)
			)
			(layer "B.SilkS")
		)
		(fp_line
			(start -1.778 2.4765)
			(end -1.778 1.5875)
			(stroke
				(width 0.1524)
				(type default)
			)
			(layer "B.SilkS")
		)
		(fp_line
			(start -1.778 -0.5715)
			(end -1.778 0.3175)
			(stroke
				(width 0.1524)
				(type default)
			)
			(layer "B.SilkS")
		)
		(fp_circle
			(center 0.9525 -0.9271)
			(end 0.8255 -0.9271)
			(stroke
				(width 0.254)
				(type default)
			)
			(fill no)
			(layer "B.SilkS")
		)
		(fp_poly
			(pts
				(xy -1.778 2.4765) (xy -0.381 2.4765) (xy -0.381 -0.5715) (xy -1.778 -0.5715)
			)
			(stroke
				(width 0)
				(type default)
			)
			(fill no)
			(layer "B.CrtYd")
		)
		(fp_line
			(start -0.381 2.4765)
			(end -1.778 2.4765)
			(stroke
				(width 0.1)
				(type default)
			)
			(layer "B.Fab")
		)
		(fp_line
			(start -0.381 -0.5715)
			(end -0.381 2.4765)
			(stroke
				(width 0.1)
				(type default)
			)
			(layer "B.Fab")
		)
		(fp_line
			(start -1.778 2.4765)
			(end -1.778 -0.5715)
			(stroke
				(width 0.1)
				(type default)
			)
			(layer "B.Fab")
		)
		(fp_line
			(start -1.778 -0.5715)
			(end -0.381 -0.5715)
			(stroke
				(width 0.1)
				(type default)
			)
			(layer "B.Fab")
		)
		(fp_circle
			(center 0.9525 -0.9271)
			(end 0.8255 -0.9271)
			(stroke
				(width 0.254)
				(type default)
			)
			(fill no)
			(layer "B.Fab")
		)
		(pad "1" smd rect
			(at 0 0)
			(size 1.143 0.508)
			(layers "B.Cu" "B.Mask" "B.Paste")
			(net "BMC_JTAG_SEL_N")
		)
		(pad "2" smd rect
			(at 0 1.905)
			(size 1.143 0.508)
			(layers "B.Cu" "B.Mask" "B.Paste")
			(net "GND")
		)
		(pad "3" smd rect
			(at -2.159 0.9525)
			(size 1.143 0.508)
			(layers "B.Cu" "B.Mask" "B.Paste")
			(net "BMC_JTAG_SEL")
		)
	)
)
